(kicad_pcb
	(version 20260206)
	(generator "pcbnew")
	(generator_version "10.0")
	(general
		(thickness 1.6)
		(legacy_teardrops no)
	)
	(paper "A4")
	(title_block
		(title "01162023_DA0F0TEBIF0_F0T_Expander_BD_F_brd_V02_OCP.brd")
		(comment 1 "Grand Teton / footprints 1584-1590 of 9728")
	)
	(layers
		(0 "F.Cu" signal "TOP")
		(4 "In1.Cu" signal "GND")
		(6 "In2.Cu" signal "VCC")
		(8 "In3.Cu" signal "VCC1")
		(10 "In4.Cu" signal "GND1")
		(12 "In5.Cu" signal "IN1")
		(14 "In6.Cu" signal "GND2")
		(16 "In7.Cu" signal "IN2")
		(18 "In8.Cu" signal "GND3")
		(20 "In9.Cu" signal "IN3")
		(22 "In10.Cu" signal "GND4")
		(24 "In11.Cu" signal "IN4")
		(26 "In12.Cu" signal "GND5")
		(28 "In13.Cu" signal "IN5")
		(30 "In14.Cu" signal "GND6")
		(32 "In15.Cu" signal "IN6")
		(34 "In16.Cu" signal "GND7")
		(2 "B.Cu" signal "BOTTOM")
		(9 "F.Adhes" user "F.Adhesive")
		(11 "B.Adhes" user "B.Adhesive")
		(13 "F.Paste" user "Package Geometry/Pastemask Top")
		(15 "B.Paste" user "Package Geometry/Pastemask Bottom")
		(5 "F.SilkS" user "Ref Des/Silkscreen Top")
		(7 "B.SilkS" user "Ref Des/Silkscreen Bottom")
		(1 "F.Mask" user "Board Geometry/Soldermask Top")
		(3 "B.Mask" user "Board Geometry/Soldermask Bottom")
		(17 "Dwgs.User" user "User.Drawings")
		(19 "Cmts.User" user "User.Comments")
		(21 "Eco1.User" user "User.Eco1")
		(23 "Eco2.User" user "User.Eco2")
		(25 "Edge.Cuts" user "Board Geometry/Outline")
		(27 "Margin" user)
		(31 "F.CrtYd" user "Package Geometry/Place Bound Top")
		(29 "B.CrtYd" user "Package Geometry/Place Bound Bottom")
		(35 "F.Fab" user "Ref Des/Assembly Top")
		(33 "B.Fab" user "Ref Des/Assembly Bottom")
	)
	(footprint ""
		(layer "F.Cu")
		(at 214.546434 -58.323734)
		(property "Reference" "PC365"
			(at 0 0 0)
			(layer "F.SilkS")
			(hide yes)
			(effects
				(font
					(size 1.27 1.27)
				)
			)
		)
		(property "Value" ""
			(at 0 0 0)
			(layer "F.Fab")
			(effects
				(font
					(size 1.27 1.27)
				)
			)
		)
		(duplicate_pad_numbers_are_jumpers no)
		(fp_line
			(start -1.524 -0.762)
			(end 1.524 -0.762)
			(stroke
				(width 0.1524)
				(type default)
			)
			(layer "F.SilkS")
		)
		(fp_line
			(start -1.524 0.762)
			(end -1.524 -0.762)
			(stroke
				(width 0.1524)
				(type default)
			)
			(layer "F.SilkS")
		)
		(fp_line
			(start 1.524 -0.762)
			(end 1.524 0.762)
			(stroke
				(width 0.1524)
				(type default)
			)
			(layer "F.SilkS")
		)
		(fp_line
			(start 1.524 0.762)
			(end -1.524 0.762)
			(stroke
				(width 0.1524)
				(type default)
			)
			(layer "F.SilkS")
		)
		(fp_line
			(start -1.1049 -0.724916)
			(end -1.1049 0.724916)
			(stroke
				(width 0.1)
				(type default)
			)
			(layer "F.Fab")
		)
		(fp_line
			(start -1.1049 0.724916)
			(end 1.1049 0.724916)
			(stroke
				(width 0.1)
				(type default)
			)
			(layer "F.Fab")
		)
		(fp_line
			(start 1.1049 -0.724916)
			(end -1.1049 -0.724916)
			(stroke
				(width 0.1)
				(type default)
			)
			(layer "F.Fab")
		)
		(fp_line
			(start 1.1049 0.724916)
			(end 1.1049 -0.724916)
			(stroke
				(width 0.1)
				(type default)
			)
			(layer "F.Fab")
		)
		(pad "1" smd rect
			(at -0.889 0 180)
			(size 1.016 1.27)
			(layers "F.Cu" "F.Mask" "F.Paste")
			(net "GND")
		)
		(pad "2" smd rect
			(at 0.889 0 180)
			(size 1.016 1.27)
			(layers "F.Cu" "F.Mask" "F.Paste")
			(net "P12V_AUX")
		)
	)
	(footprint ""
		(layer "F.Cu")
		(at 291.303202 -59.571636 90)
		(property "Reference" "PR281"
			(at 0 0 90)
			(layer "F.SilkS")
			(hide yes)
			(effects
				(font
					(size 1.27 1.27)
				)
			)
		)
		(property "Value" ""
			(at 0 0 90)
			(layer "F.Fab")
			(effects
				(font
					(size 1.27 1.27)
				)
			)
		)
		(duplicate_pad_numbers_are_jumpers no)
		(fp_line
			(start 0.7874 -0.4064)
			(end 0.7874 0.4064)
			(stroke
				(width 0.1524)
				(type default)
			)
			(layer "F.SilkS")
		)
		(fp_line
			(start -0.7874 -0.4064)
			(end 0.7874 -0.4064)
			(stroke
				(width 0.1524)
				(type default)
			)
			(layer "F.SilkS")
		)
		(fp_line
			(start 0.7874 0.4064)
			(end -0.7874 0.4064)
			(stroke
				(width 0.1524)
				(type default)
			)
			(layer "F.SilkS")
		)
		(fp_line
			(start -0.7874 0.4064)
			(end -0.7874 -0.4064)
			(stroke
				(width 0.1524)
				(type default)
			)
			(layer "F.SilkS")
		)
		(fp_line
			(start -0.12065 -0.305054)
			(end -0.12065 -0.2794)
			(stroke
				(width 0.1)
				(type default)
			)
			(layer "F.Fab")
		)
		(fp_line
			(start -0.67945 -0.305054)
			(end -0.12065 -0.305054)
			(stroke
				(width 0.1)
				(type default)
			)
			(layer "F.Fab")
		)
		(fp_line
			(start 0.67945 -0.3048)
			(end 0.67945 0.3048)
			(stroke
				(width 0.1)
				(type default)
			)
			(layer "F.Fab")
		)
		(fp_line
			(start 0.12065 -0.3048)
			(end 0.67945 -0.3048)
			(stroke
				(width 0.1)
				(type default)
			)
			(layer "F.Fab")
		)
		(fp_line
			(start 0.12065 -0.2794)
			(end 0.12065 -0.3048)
			(stroke
				(width 0.1)
				(type default)
			)
			(layer "F.Fab")
		)
		(fp_line
			(start -0.12065 -0.2794)
			(end 0.12065 -0.2794)
			(stroke
				(width 0.1)
				(type default)
			)
			(layer "F.Fab")
		)
		(fp_line
			(start 0.120396 0.2794)
			(end -0.12065 0.2794)
			(stroke
				(width 0.1)
				(type default)
			)
			(layer "F.Fab")
		)
		(fp_line
			(start -0.12065 0.2794)
			(end -0.12065 0.3048)
			(stroke
				(width 0.1)
				(type default)
			)
			(layer "F.Fab")
		)
		(fp_line
			(start 0.67945 0.3048)
			(end 0.120396 0.3048)
			(stroke
				(width 0.1)
				(type default)
			)
			(layer "F.Fab")
		)
		(fp_line
			(start 0.120396 0.3048)
			(end 0.120396 0.2794)
			(stroke
				(width 0.1)
				(type default)
			)
			(layer "F.Fab")
		)
		(fp_line
			(start -0.12065 0.3048)
			(end -0.67945 0.3048)
			(stroke
				(width 0.1)
				(type default)
			)
			(layer "F.Fab")
		)
		(fp_line
			(start -0.67945 0.3048)
			(end -0.67945 -0.305054)
			(stroke
				(width 0.1)
				(type default)
			)
			(layer "F.Fab")
		)
		(pad "1" smd circle
			(at -0.40005 0 90)
			(size 0 0)
			(layers "F.Cu" "F.Mask" "F.Paste")
			(net "P3V3_SSD10_OCP")
		)
		(pad "2" smd circle
			(at 0.40005 0 90)
			(size 0 0)
			(layers "F.Cu" "F.Mask" "F.Paste")
			(net "GND")
		)
	)
	(footprint ""
		(layer "F.Cu")
		(at 387.06044 -116.7384)
		(property "Reference" "R345"
			(at 0 0 0)
			(layer "F.SilkS")
			(hide yes)
			(effects
				(font
					(size 1.27 1.27)
				)
			)
		)
		(property "Value" ""
			(at 0 0 0)
			(layer "F.Fab")
			(effects
				(font
					(size 1.27 1.27)
				)
			)
		)
		(duplicate_pad_numbers_are_jumpers no)
		(fp_line
			(start -0.7874 -0.4064)
			(end 0.7874 -0.4064)
			(stroke
				(width 0.1524)
				(type default)
			)
			(layer "F.SilkS")
		)
		(fp_line
			(start -0.7874 0.4064)
			(end -0.7874 -0.4064)
			(stroke
				(width 0.1524)
				(type default)
			)
			(layer "F.SilkS")
		)
		(fp_line
			(start 0.7874 -0.4064)
			(end 0.7874 0.4064)
			(stroke
				(width 0.1524)
				(type default)
			)
			(layer "F.SilkS")
		)
		(fp_line
			(start 0.7874 0.4064)
			(end -0.7874 0.4064)
			(stroke
				(width 0.1524)
				(type default)
			)
			(layer "F.SilkS")
		)
		(fp_line
			(start -0.67945 -0.305054)
			(end -0.12065 -0.305054)
			(stroke
				(width 0.1)
				(type default)
			)
			(layer "F.Fab")
		)
		(fp_line
			(start -0.67945 0.3048)
			(end -0.67945 -0.305054)
			(stroke
				(width 0.1)
				(type default)
			)
			(layer "F.Fab")
		)
		(fp_line
			(start -0.12065 -0.305054)
			(end -0.12065 -0.2794)
			(stroke
				(width 0.1)
				(type default)
			)
			(layer "F.Fab")
		)
		(fp_line
			(start -0.12065 -0.2794)
			(end 0.12065 -0.2794)
			(stroke
				(width 0.1)
				(type default)
			)
			(layer "F.Fab")
		)
		(fp_line
			(start -0.12065 0.2794)
			(end -0.12065 0.3048)
			(stroke
				(width 0.1)
				(type default)
			)
			(layer "F.Fab")
		)
		(fp_line
			(start -0.12065 0.3048)
			(end -0.67945 0.3048)
			(stroke
				(width 0.1)
				(type default)
			)
			(layer "F.Fab")
		)
		(fp_line
			(start 0.120396 0.2794)
			(end -0.12065 0.2794)
			(stroke
				(width 0.1)
				(type default)
			)
			(layer "F.Fab")
		)
		(fp_line
			(start 0.120396 0.3048)
			(end 0.120396 0.2794)
			(stroke
				(width 0.1)
				(type default)
			)
			(layer "F.Fab")
		)
		(fp_line
			(start 0.12065 -0.3048)
			(end 0.67945 -0.3048)
			(stroke
				(width 0.1)
				(type default)
			)
			(layer "F.Fab")
		)
		(fp_line
			(start 0.12065 -0.2794)
			(end 0.12065 -0.3048)
			(stroke
				(width 0.1)
				(type default)
			)
			(layer "F.Fab")
		)
		(fp_line
			(start 0.67945 -0.3048)
			(end 0.67945 0.3048)
			(stroke
				(width 0.1)
				(type default)
			)
			(layer "F.Fab")
		)
		(fp_line
			(start 0.67945 0.3048)
			(end 0.120396 0.3048)
			(stroke
				(width 0.1)
				(type default)
			)
			(layer "F.Fab")
		)
		(pad "1" smd circle
			(at -0.40005 0)
			(size 0 0)
			(layers "F.Cu" "F.Mask" "F.Paste")
			(net "PRSNT_NIC6_N")
		)
		(pad "2" smd circle
			(at 0.40005 0)
			(size 0 0)
			(layers "F.Cu" "F.Mask" "F.Paste")
			(net "PRSNTB0_NIC6_N")
		)
	)
	(footprint ""
		(layer "F.Cu")
		(at 146.253454 -297.791632)
		(property "Reference" "L104"
			(at 0 0 0)
			(layer "F.SilkS")
			(hide yes)
			(effects
				(font
					(size 1.27 1.27)
				)
			)
		)
		(property "Value" ""
			(at 0 0 0)
			(layer "F.Fab")
			(effects
				(font
					(size 1.27 1.27)
				)
			)
		)
		(duplicate_pad_numbers_are_jumpers no)
		(fp_line
			(start -1.63576 -0.8128)
			(end -1.63576 0.8128)
			(stroke
				(width 0.1524)
				(type default)
			)
			(layer "F.SilkS")
		)
		(fp_line
			(start -1.63576 -0.8128)
			(end 1.63576 -0.8128)
			(stroke
				(width 0.1524)
				(type default)
			)
			(layer "F.SilkS")
		)
		(fp_line
			(start 1.63576 -0.8128)
			(end 1.63576 0.8128)
			(stroke
				(width 0.1524)
				(type default)
			)
			(layer "F.SilkS")
		)
		(fp_line
			(start 1.63576 0.8128)
			(end -1.63576 0.8128)
			(stroke
				(width 0.1524)
				(type default)
			)
			(layer "F.SilkS")
		)
		(fp_line
			(start -1.56083 -0.738632)
			(end -1.56083 0.7366)
			(stroke
				(width 0.1)
				(type default)
			)
			(layer "F.Fab")
		)
		(fp_line
			(start -1.56083 0.7366)
			(end -1.524 0.7366)
			(stroke
				(width 0.1)
				(type default)
			)
			(layer "F.Fab")
		)
		(fp_line
			(start -1.524 0.7366)
			(end 1.524 0.7366)
			(stroke
				(width 0.1)
				(type default)
			)
			(layer "F.Fab")
		)
		(fp_line
			(start 1.524 0.7366)
			(end 1.560576 0.7366)
			(stroke
				(width 0.1)
				(type default)
			)
			(layer "F.Fab")
		)
		(fp_line
			(start 1.560576 -0.738632)
			(end -1.56083 -0.738632)
			(stroke
				(width 0.1)
				(type default)
			)
			(layer "F.Fab")
		)
		(fp_line
			(start 1.560576 0.7366)
			(end 1.560576 -0.738632)
			(stroke
				(width 0.1)
				(type default)
			)
			(layer "F.Fab")
		)
		(pad "1" smd rect
			(at -0.94996 0 180)
			(size 1.1176 1.3716)
			(layers "F.Cu" "F.Mask" "F.Paste")
			(net "P1V8_PLL0_PEX1")
		)
		(pad "2" smd rect
			(at 0.94996 0 180)
			(size 1.1176 1.3716)
			(layers "F.Cu" "F.Mask" "F.Paste")
			(net "PCEPLL0_VDDA18_PEX1")
		)
	)
	(footprint ""
		(layer "F.Cu")
		(at 243.217954 -178.519328 -90)
		(property "Reference" "R4251"
			(at 0 0 270)
			(layer "F.SilkS")
			(hide yes)
			(effects
				(font
					(size 1.27 1.27)
				)
			)
		)
		(property "Value" ""
			(at 0 0 270)
			(layer "F.Fab")
			(effects
				(font
					(size 1.27 1.27)
				)
			)
		)
		(duplicate_pad_numbers_are_jumpers no)
		(fp_line
			(start -0.7874 0.4064)
			(end -0.7874 -0.4064)
			(stroke
				(width 0.1524)
				(type default)
			)
			(layer "F.SilkS")
		)
		(fp_line
			(start 0.7874 0.4064)
			(end -0.7874 0.4064)
			(stroke
				(width 0.1524)
				(type default)
			)
			(layer "F.SilkS")
		)
		(fp_line
			(start -0.7874 -0.4064)
			(end 0.7874 -0.4064)
			(stroke
				(width 0.1524)
				(type default)
			)
			(layer "F.SilkS")
		)
		(fp_line
			(start 0.7874 -0.4064)
			(end 0.7874 0.4064)
			(stroke
				(width 0.1524)
				(type default)
			)
			(layer "F.SilkS")
		)
		(fp_line
			(start -0.67945 0.3048)
			(end -0.67945 -0.305054)
			(stroke
				(width 0.1)
				(type default)
			)
			(layer "F.Fab")
		)
		(fp_line
			(start -0.12065 0.3048)
			(end -0.67945 0.3048)
			(stroke
				(width 0.1)
				(type default)
			)
			(layer "F.Fab")
		)
		(fp_line
			(start 0.120396 0.3048)
			(end 0.120396 0.2794)
			(stroke
				(width 0.1)
				(type default)
			)
			(layer "F.Fab")
		)
		(fp_line
			(start 0.67945 0.3048)
			(end 0.120396 0.3048)
			(stroke
				(width 0.1)
				(type default)
			)
			(layer "F.Fab")
		)
		(fp_line
			(start -0.12065 0.2794)
			(end -0.12065 0.3048)
			(stroke
				(width 0.1)
				(type default)
			)
			(layer "F.Fab")
		)
		(fp_line
			(start 0.120396 0.2794)
			(end -0.12065 0.2794)
			(stroke
				(width 0.1)
				(type default)
			)
			(layer "F.Fab")
		)
		(fp_line
			(start -0.12065 -0.2794)
			(end 0.12065 -0.2794)
			(stroke
				(width 0.1)
				(type default)
			)
			(layer "F.Fab")
		)
		(fp_line
			(start 0.12065 -0.2794)
			(end 0.12065 -0.3048)
			(stroke
				(width 0.1)
				(type default)
			)
			(layer "F.Fab")
		)
		(fp_line
			(start 0.12065 -0.3048)
			(end 0.67945 -0.3048)
			(stroke
				(width 0.1)
				(type default)
			)
			(layer "F.Fab")
		)
		(fp_line
			(start 0.67945 -0.3048)
			(end 0.67945 0.3048)
			(stroke
				(width 0.1)
				(type default)
			)
			(layer "F.Fab")
		)
		(fp_line
			(start -0.67945 -0.305054)
			(end -0.12065 -0.305054)
			(stroke
				(width 0.1)
				(type default)
			)
			(layer "F.Fab")
		)
		(fp_line
			(start -0.12065 -0.305054)
			(end -0.12065 -0.2794)
			(stroke
				(width 0.1)
				(type default)
			)
			(layer "F.Fab")
		)
		(pad "1" smd circle
			(at -0.40005 0 270)
			(size 0 0)
			(layers "F.Cu" "F.Mask" "F.Paste")
			(net "BIC_RST_PWRGD_RSMRST_R")
		)
		(pad "2" smd circle
			(at 0.40005 0 270)
			(size 0 0)
			(layers "F.Cu" "F.Mask" "F.Paste")
			(net "GND")
		)
	)
	(footprint ""
		(layer "F.Cu")
		(at 270.807942 -162.044126 180)
		(property "Reference" "R226"
			(at 0 0 180)
			(layer "F.SilkS")
			(hide yes)
			(effects
				(font
					(size 1.27 1.27)
				)
			)
		)
		(property "Value" ""
			(at 0 0 180)
			(layer "F.Fab")
			(effects
				(font
					(size 1.27 1.27)
				)
			)
		)
		(duplicate_pad_numbers_are_jumpers no)
		(fp_line
			(start 0.7874 0.4064)
			(end -0.7874 0.4064)
			(stroke
				(width 0.1524)
				(type default)
			)
			(layer "F.SilkS")
		)
		(fp_line
			(start 0.7874 -0.4064)
			(end 0.7874 0.4064)
			(stroke
				(width 0.1524)
				(type default)
			)
			(layer "F.SilkS")
		)
		(fp_line
			(start -0.7874 0.4064)
			(end -0.7874 -0.4064)
			(stroke
				(width 0.1524)
				(type default)
			)
			(layer "F.SilkS")
		)
		(fp_line
			(start -0.7874 -0.4064)
			(end 0.7874 -0.4064)
			(stroke
				(width 0.1524)
				(type default)
			)
			(layer "F.SilkS")
		)
		(fp_line
			(start 0.67945 0.3048)
			(end 0.120396 0.3048)
			(stroke
				(width 0.1)
				(type default)
			)
			(layer "F.Fab")
		)
		(fp_line
			(start 0.67945 -0.3048)
			(end 0.67945 0.3048)
			(stroke
				(width 0.1)
				(type default)
			)
			(layer "F.Fab")
		)
		(fp_line
			(start 0.12065 -0.2794)
			(end 0.12065 -0.3048)
			(stroke
				(width 0.1)
				(type default)
			)
			(layer "F.Fab")
		)
		(fp_line
			(start 0.12065 -0.3048)
			(end 0.67945 -0.3048)
			(stroke
				(width 0.1)
				(type default)
			)
			(layer "F.Fab")
		)
		(fp_line
			(start 0.120396 0.3048)
			(end 0.120396 0.2794)
			(stroke
				(width 0.1)
				(type default)
			)
			(layer "F.Fab")
		)
		(fp_line
			(start 0.120396 0.2794)
			(end -0.12065 0.2794)
			(stroke
				(width 0.1)
				(type default)
			)
			(layer "F.Fab")
		)
		(fp_line
			(start -0.12065 0.3048)
			(end -0.67945 0.3048)
			(stroke
				(width 0.1)
				(type default)
			)
			(layer "F.Fab")
		)
		(fp_line
			(start -0.12065 0.2794)
			(end -0.12065 0.3048)
			(stroke
				(width 0.1)
				(type default)
			)
			(layer "F.Fab")
		)
		(fp_line
			(start -0.12065 -0.2794)
			(end 0.12065 -0.2794)
			(stroke
				(width 0.1)
				(type default)
			)
			(layer "F.Fab")
		)
		(fp_line
			(start -0.12065 -0.305054)
			(end -0.12065 -0.2794)
			(stroke
				(width 0.1)
				(type default)
			)
			(layer "F.Fab")
		)
		(fp_line
			(start -0.67945 0.3048)
			(end -0.67945 -0.305054)
			(stroke
				(width 0.1)
				(type default)
			)
			(layer "F.Fab")
		)
		(fp_line
			(start -0.67945 -0.305054)
			(end -0.12065 -0.305054)
			(stroke
				(width 0.1)
				(type default)
			)
			(layer "F.Fab")
		)
		(pad "1" smd circle
			(at -0.40005 0 180)
			(size 0 0)
			(layers "F.Cu" "F.Mask" "F.Paste")
			(net "PWRGD_NIC4_PWR_GOOD")
		)
		(pad "2" smd circle
			(at 0.40005 0 180)
			(size 0 0)
			(layers "F.Cu" "F.Mask" "F.Paste")
			(net "GND")
		)
	)
	(footprint ""
		(layer "F.Cu")
		(at 458.567536 -306.805076 -90)
		(property "Reference" "PR182"
			(at 0 0 270)
			(layer "F.SilkS")
			(hide yes)
			(effects
				(font
					(size 1.27 1.27)
				)
			)
		)
		(property "Value" ""
			(at 0 0 270)
			(layer "F.Fab")
			(effects
				(font
					(size 1.27 1.27)
				)
			)
		)
		(duplicate_pad_numbers_are_jumpers no)
		(fp_line
			(start -0.7874 0.4064)
			(end -0.7874 -0.4064)
			(stroke
				(width 0.1524)
				(type default)
			)
			(layer "F.SilkS")
		)
		(fp_line
			(start 0.7874 0.4064)
			(end -0.7874 0.4064)
			(stroke
				(width 0.1524)
				(type default)
			)
			(layer "F.SilkS")
		)
		(fp_line
			(start -0.7874 -0.4064)
			(end 0.7874 -0.4064)
			(stroke
				(width 0.1524)
				(type default)
			)
			(layer "F.SilkS")
		)
		(fp_line
			(start 0.7874 -0.4064)
			(end 0.7874 0.4064)
			(stroke
				(width 0.1524)
				(type default)
			)
			(layer "F.SilkS")
		)
		(fp_line
			(start -0.67945 0.3048)
			(end -0.67945 -0.305054)
			(stroke
				(width 0.1)
				(type default)
			)
			(layer "F.Fab")
		)
		(fp_line
			(start -0.12065 0.3048)
			(end -0.67945 0.3048)
			(stroke
				(width 0.1)
				(type default)
			)
			(layer "F.Fab")
		)
		(fp_line
			(start 0.120396 0.3048)
			(end 0.120396 0.2794)
			(stroke
				(width 0.1)
				(type default)
			)
			(layer "F.Fab")
		)
		(fp_line
			(start 0.67945 0.3048)
			(end 0.120396 0.3048)
			(stroke
				(width 0.1)
				(type default)
			)
			(layer "F.Fab")
		)
		(fp_line
			(start -0.12065 0.2794)
			(end -0.12065 0.3048)
			(stroke
				(width 0.1)
				(type default)
			)
			(layer "F.Fab")
		)
		(fp_line
			(start 0.120396 0.2794)
			(end -0.12065 0.2794)
			(stroke
				(width 0.1)
				(type default)
			)
			(layer "F.Fab")
		)
		(fp_line
			(start -0.12065 -0.2794)
			(end 0.12065 -0.2794)
			(stroke
				(width 0.1)
				(type default)
			)
			(layer "F.Fab")
		)
		(fp_line
			(start 0.12065 -0.2794)
			(end 0.12065 -0.3048)
			(stroke
				(width 0.1)
				(type default)
			)
			(layer "F.Fab")
		)
		(fp_line
			(start 0.12065 -0.3048)
			(end 0.67945 -0.3048)
			(stroke
				(width 0.1)
				(type default)
			)
			(layer "F.Fab")
		)
		(fp_line
			(start 0.67945 -0.3048)
			(end 0.67945 0.3048)
			(stroke
				(width 0.1)
				(type default)
			)
			(layer "F.Fab")
		)
		(fp_line
			(start -0.67945 -0.305054)
			(end -0.12065 -0.305054)
			(stroke
				(width 0.1)
				(type default)
			)
			(layer "F.Fab")
		)
		(fp_line
			(start -0.12065 -0.305054)
			(end -0.12065 -0.2794)
			(stroke
				(width 0.1)
				(type default)
			)
			(layer "F.Fab")
		)
		(pad "1" smd circle
			(at -0.40005 0 270)
			(size 0 0)
			(layers "F.Cu" "F.Mask" "F.Paste")
			(net "P1V25_PEX3_CS")
		)
		(pad "2" smd circle
			(at 0.40005 0 270)
			(size 0 0)
			(layers "F.Cu" "F.Mask" "F.Paste")
			(net "GND")
		)
	)
)
